# BASEBOARD_FAB2 (Tioga Pass) — schematic netlist excerpt (pin names and nets, part order shuffled) for the footprints in the layout excerpt that follows; sources: Cadence DE-HDL packaged netlist, KiCad conversion of Wiwynn_Tioga_Pass_MB.brd

C2D21  CAP_A  22.0UF 4V 20% X6S  pkg 0603V  page 76 : A = PVCCIN_CPU1 ; B = GND
C14W2  CAP_A  0.1UF 16V 10% X7R  pkg 0402V  page 248 : A = P3V3 ; B = GND
C7C18  CAP  0.22UF 16V 10% X7R  pkg 0402  page 212 : A = P5V_STBY ; B = GND

(kicad_pcb
	(version 20260206)
	(generator "pcbnew")
	(generator_version "10.0")
	(general
		(thickness 1.6)
		(legacy_teardrops no)
	)
	(paper "A4")
	(title_block
		(title "Wiwynn_Tioga_Pass_MB.brd")
		(comment 1 "Tioga Pass / footprints 1929-1931 of 4770")
	)
	(layers
		(0 "F.Cu" signal "TOP")
		(4 "In1.Cu" signal "L2GND")
		(6 "In2.Cu" signal "L3")
		(8 "In3.Cu" signal "L4GND")
		(10 "In4.Cu" signal "L5")
		(12 "In5.Cu" signal "L6GND")
		(14 "In6.Cu" signal "L7VCC")
		(16 "In7.Cu" signal "L8VCC")
		(18 "In8.Cu" signal "L9GND")
		(20 "In9.Cu" signal "L10")
		(22 "In10.Cu" signal "L11GND")
		(24 "In11.Cu" signal "L12")
		(26 "In12.Cu" signal "L13GND")
		(2 "B.Cu" signal "BOTTOM")
		(9 "F.Adhes" user "F.Adhesive")
		(11 "B.Adhes" user "B.Adhesive")
		(13 "F.Paste" user "Package Geometry/Pastemask Top")
		(15 "B.Paste" user "Package Geometry/Pastemask Bottom")
		(5 "F.SilkS" user "Ref Des/Silkscreen Top")
		(7 "B.SilkS" user "Ref Des/Silkscreen Bottom")
		(1 "F.Mask" user "Board Geometry/Soldermask Top")
		(3 "B.Mask" user "Board Geometry/Soldermask Bottom")
		(17 "Dwgs.User" user "User.Drawings")
		(19 "Cmts.User" user "User.Comments")
		(21 "Eco1.User" user "User.Eco1")
		(23 "Eco2.User" user "User.Eco2")
		(25 "Edge.Cuts" user "Board Geometry/Outline")
		(27 "Margin" user)
		(31 "F.CrtYd" user "Package Geometry/Place Bound Top")
		(29 "B.CrtYd" user "Package Geometry/Place Bound Bottom")
		(35 "F.Fab" user "Ref Des/Assembly Top")
		(33 "B.Fab" user "Ref Des/Assembly Bottom")
	)
	(footprint ""
		(layer "F.Cu")
		(at 347.778578 -101.363272 -90)
		(property "Reference" "C7C18"
			(at 0 0 270)
			(layer "F.SilkS")
			(hide yes)
			(effects
				(font
					(size 1.27 1.27)
				)
			)
		)
		(property "Value" ""
			(at 0 0 270)
			(layer "F.Fab")
			(effects
				(font
					(size 1.27 1.27)
				)
			)
		)
		(duplicate_pad_numbers_are_jumpers no)
		(fp_poly
			(pts
				(xy 0.3048 -0.1016) (xy 0.3048 0.9906) (xy -0.3048 0.9906) (xy -0.3048 -0.1016)
			)
			(stroke
				(width 0)
				(type default)
			)
			(fill no)
			(layer "F.CrtYd")
		)
		(fp_line
			(start -0.3048 0.9906)
			(end 0.3048 0.9906)
			(stroke
				(width 0.1)
				(type default)
			)
			(layer "F.Fab")
		)
		(fp_line
			(start 0.3048 0.9906)
			(end 0.3048 -0.1016)
			(stroke
				(width 0.1)
				(type default)
			)
			(layer "F.Fab")
		)
		(fp_line
			(start -0.3048 -0.1016)
			(end -0.3048 0.9906)
			(stroke
				(width 0.1)
				(type default)
			)
			(layer "F.Fab")
		)
		(fp_line
			(start 0.3048 -0.1016)
			(end -0.3048 -0.1016)
			(stroke
				(width 0.1)
				(type default)
			)
			(layer "F.Fab")
		)
		(pad "1" smd rect
			(at 0 0 270)
			(size 0.508 0.508)
			(layers "F.Cu" "F.Mask" "F.Paste")
			(net "P5V_STBY")
		)
		(pad "2" smd rect
			(at 0 0.889 270)
			(size 0.508 0.508)
			(layers "F.Cu" "F.Mask" "F.Paste")
			(net "GND")
		)
		(zone
			(layer "F.Cu")
			(hatch none 0.5)
			(connect_pads
				(clearance 0)
			)
			(min_thickness 0.25)
			(keepout
				(tracks not_allowed)
				(vias allowed)
				(pads allowed)
				(copperpour not_allowed)
				(footprints allowed)
			)
			(placement
				(enabled no)
				(sheetname "")
			)
			(fill
				(thermal_gap 0.5)
				(thermal_bridge_width 0.5)
				(island_removal_mode 0)
			)
			(polygon
				(pts
					(xy 347.143578 -101.617272) (xy 347.143578 -101.109272) (xy 347.524578 -101.109272) (xy 347.524578 -101.617272)
				)
			)
		)
		(zone
			(layer "F.Cu")
			(hatch none 0.5)
			(connect_pads
				(clearance 0)
			)
			(min_thickness 0.25)
			(keepout
				(tracks allowed)
				(vias not_allowed)
				(pads allowed)
				(copperpour not_allowed)
				(footprints allowed)
			)
			(placement
				(enabled no)
				(sheetname "")
			)
			(fill
				(thermal_gap 0.5)
				(thermal_bridge_width 0.5)
				(island_removal_mode 0)
			)
			(polygon
				(pts
					(xy 347.524578 -101.617272) (xy 347.524578 -101.109272) (xy 347.143578 -101.109272) (xy 347.143578 -101.617272)
				)
			)
		)
	)
	(footprint ""
		(layer "F.Cu")
		(at 95.69704 -77.636116)
		(property "Reference" "C2D21"
			(at 0 0 0)
			(layer "F.SilkS")
			(hide yes)
			(effects
				(font
					(size 1.27 1.27)
				)
			)
		)
		(property "Value" ""
			(at 0 0 0)
			(layer "F.Fab")
			(effects
				(font
					(size 1.27 1.27)
				)
			)
		)
		(duplicate_pad_numbers_are_jumpers no)
		(fp_poly
			(pts
				(xy -0.4953 -0.2032) (xy 0.4953 -0.2032) (xy 0.4953 1.6002) (xy -0.4953 1.6002)
			)
			(stroke
				(width 0)
				(type default)
			)
			(fill no)
			(layer "F.CrtYd")
		)
		(fp_line
			(start -0.4953 -0.2032)
			(end 0.4953 -0.2032)
			(stroke
				(width 0.1)
				(type default)
			)
			(layer "F.Fab")
		)
		(fp_line
			(start -0.4953 1.6002)
			(end -0.4953 -0.2032)
			(stroke
				(width 0.1)
				(type default)
			)
			(layer "F.Fab")
		)
		(fp_line
			(start 0.4953 -0.2032)
			(end 0.4953 1.6002)
			(stroke
				(width 0.1)
				(type default)
			)
			(layer "F.Fab")
		)
		(fp_line
			(start 0.4953 1.6002)
			(end -0.4953 1.6002)
			(stroke
				(width 0.1)
				(type default)
			)
			(layer "F.Fab")
		)
		(pad "1" smd rect
			(at 0 0)
			(size 0.762 0.889)
			(layers "F.Cu" "F.Mask" "F.Paste")
			(net "PVCCIN_CPU1")
		)
		(pad "2" smd rect
			(at 0 1.397)
			(size 0.762 0.889)
			(layers "F.Cu" "F.Mask" "F.Paste")
			(net "GND")
		)
		(zone
			(layer "F.Cu")
			(hatch none 0.5)
			(connect_pads
				(clearance 0)
			)
			(min_thickness 0.25)
			(keepout
				(tracks not_allowed)
				(vias allowed)
				(pads allowed)
				(copperpour not_allowed)
				(footprints allowed)
			)
			(placement
				(enabled no)
				(sheetname "")
			)
			(fill
				(thermal_gap 0.5)
				(thermal_bridge_width 0.5)
				(island_removal_mode 0)
			)
			(polygon
				(pts
					(xy 95.31604 -77.191616) (xy 96.07804 -77.191616) (xy 96.07804 -76.683616) (xy 95.31604 -76.683616)
				)
			)
		)
	)
	(footprint ""
		(layer "F.Cu")
		(at 389.439912 -81.906364 90)
		(property "Reference" "C14W2"
			(at -0.8382 -0.67818 90)
			(unlocked yes)
			(layer "F.SilkS")
			(effects
				(font
					(size 0.4064 0.254)
					(thickness 0.1524)
				)
				(justify left)
			)
		)
		(property "Value" ""
			(at 0 0 90)
			(layer "F.Fab")
			(effects
				(font
					(size 1.27 1.27)
				)
			)
		)
		(duplicate_pad_numbers_are_jumpers no)
		(fp_poly
			(pts
				(xy 0.3048 -0.1016) (xy 0.3048 0.9906) (xy -0.3048 0.9906) (xy -0.3048 -0.1016)
			)
			(stroke
				(width 0)
				(type default)
			)
			(fill no)
			(layer "F.CrtYd")
		)
		(fp_line
			(start 0.3048 -0.1016)
			(end -0.3048 -0.1016)
			(stroke
				(width 0.1)
				(type default)
			)
			(layer "F.Fab")
		)
		(fp_line
			(start -0.3048 -0.1016)
			(end -0.3048 0.9906)
			(stroke
				(width 0.1)
				(type default)
			)
			(layer "F.Fab")
		)
		(fp_line
			(start 0.3048 0.9906)
			(end 0.3048 -0.1016)
			(stroke
				(width 0.1)
				(type default)
			)
			(layer "F.Fab")
		)
		(fp_line
			(start -0.3048 0.9906)
			(end 0.3048 0.9906)
			(stroke
				(width 0.1)
				(type default)
			)
			(layer "F.Fab")
		)
		(pad "1" smd rect
			(at 0 0 90)
			(size 0.508 0.508)
			(layers "F.Cu" "F.Mask" "F.Paste")
			(net "P3V3")
		)
		(pad "2" smd rect
			(at 0 0.889 90)
			(size 0.508 0.508)
			(layers "F.Cu" "F.Mask" "F.Paste")
			(net "GND")
		)
		(zone
			(layer "F.Cu")
			(hatch none 0.5)
			(connect_pads
				(clearance 0)
			)
			(min_thickness 0.25)
			(keepout
				(tracks allowed)
				(vias not_allowed)
				(pads allowed)
				(copperpour not_allowed)
				(footprints allowed)
			)
			(placement
				(enabled no)
				(sheetname "")
			)
			(fill
				(thermal_gap 0.5)
				(thermal_bridge_width 0.5)
				(island_removal_mode 0)
			)
			(polygon
				(pts
					(xy 389.693912 -81.652364) (xy 389.693912 -82.160364) (xy 390.074912 -82.160364) (xy 390.074912 -81.652364)
				)
			)
		)
		(zone
			(layer "F.Cu")
			(hatch none 0.5)
			(connect_pads
				(clearance 0)
			)
			(min_thickness 0.25)
			(keepout
				(tracks not_allowed)
				(vias allowed)
				(pads allowed)
				(copperpour not_allowed)
				(footprints allowed)
			)
			(placement
				(enabled no)
				(sheetname "")
			)
			(fill
				(thermal_gap 0.5)
				(thermal_bridge_width 0.5)
				(island_removal_mode 0)
			)
			(polygon
				(pts
					(xy 390.074912 -81.652364) (xy 390.074912 -82.160364) (xy 389.693912 -82.160364) (xy 389.693912 -81.652364)
				)
			)
		)
	)
)
